(kicad_pcb
	(version 20260206)
	(generator "pcbnew")
	(generator_version "10.0")
	(general
		(thickness 1.6)
		(legacy_teardrops no)
	)
	(paper "A4")
	(title_block
		(title "v1-tray-backplane — T6M_tray_BP_c_1023_1120.brd")
		(comment 1 "Open CloudServer (Microsoft) / footprint 31 of 170 (J7), pads 1-54 of 54")
	)
	(layers
		(0 "F.Cu" signal "TOP")
		(4 "In1.Cu" signal "GND")
		(6 "In2.Cu" signal "IN1")
		(8 "In3.Cu" signal "VCC")
		(10 "In4.Cu" signal "VCC1")
		(12 "In5.Cu" signal "IN2")
		(14 "In6.Cu" signal "GND1")
		(2 "B.Cu" signal "BOTTOM")
		(9 "F.Adhes" user "F.Adhesive")
		(11 "B.Adhes" user "B.Adhesive")
		(13 "F.Paste" user "Package Geometry/Pastemask Top")
		(15 "B.Paste" user "Package Geometry/Pastemask Bottom")
		(5 "F.SilkS" user "Ref Des/Silkscreen Top")
		(7 "B.SilkS" user "Ref Des/Silkscreen Bottom")
		(1 "F.Mask" user "Board Geometry/Soldermask Top")
		(3 "B.Mask" user "Board Geometry/Soldermask Bottom")
		(17 "Dwgs.User" user "User.Drawings")
		(19 "Cmts.User" user "User.Comments")
		(21 "Eco1.User" user "User.Eco1")
		(23 "Eco2.User" user "User.Eco2")
		(25 "Edge.Cuts" user "Board Geometry/Outline")
		(27 "Margin" user)
		(31 "F.CrtYd" user "Package Geometry/Place Bound Top")
		(29 "B.CrtYd" user "Package Geometry/Place Bound Bottom")
		(35 "F.Fab" user "Ref Des/Assembly Top")
		(33 "B.Fab" user "Ref Des/Assembly Bottom")
	)
	(footprint ""
		(layer "F.Cu")
		(at 349.530162 -2.100072 180)
		(property "Reference" "J7"
			(at -4.826762 -0.729234 90)
			(unlocked yes)
			(layer "F.SilkS")
			(effects
				(font
					(size 0.7874 0.5842)
					(thickness 0.1524)
				)
				(justify left)
			)
		)
		(property "Value" ""
			(at 0 0 180)
			(layer "F.Fab")
			(effects
				(font
					(size 1.27 1.27)
				)
			)
		)
		(duplicate_pad_numbers_are_jumpers no)
		(pad "A1" thru_hole rect
			(at 0 0)
			(size 0.9144 0.9144)
			(drill 0.508)
			(layers "*.Cu" "*.Mask")
			(remove_unused_layers no)
			(net "ENET1G_3_MDI0P")
			(clearance 0.0508)
			(thermal_gap 0.0508)
			(padstack
				(mode front_inner_back)
				(layer "Inner"
					(shape circle)
					(size 0.9144 0.9144)
					(clearance 0.0508)
				)
				(layer "B.Cu"
					(shape rect)
					(size 0.9144 0.9144)
					(clearance 0.0508)
				)
			)
		)
		(pad "A2" thru_hole circle
			(at 1.999996 -0.100076)
			(size 0.9144 0.9144)
			(drill 0.508)
			(layers "*.Cu" "*.Mask")
			(remove_unused_layers no)
			(net "GND")
			(clearance 0.0508)
			(thermal_gap 0.0508)
		)
		(pad "A3" thru_hole circle
			(at 3.999992 0)
			(size 0.9144 0.9144)
			(drill 0.508)
			(layers "*.Cu" "*.Mask")
			(remove_unused_layers no)
			(net "ENET1G_3_MDI3P")
			(clearance 0.0508)
			(thermal_gap 0.0508)
		)
		(pad "A4" thru_hole circle
			(at 5.999988 -0.100076)
			(size 0.9144 0.9144)
			(drill 0.508)
			(layers "*.Cu" "*.Mask")
			(remove_unused_layers no)
			(net "GND")
			(clearance 0.0508)
			(thermal_gap 0.0508)
		)
		(pad "A5" thru_hole circle
			(at 7.999984 0)
			(size 0.9144 0.9144)
			(drill 0.508)
			(layers "*.Cu" "*.Mask")
			(remove_unused_layers no)
			(net "ENET1G_4_MDI1P")
			(clearance 0.0508)
			(thermal_gap 0.0508)
		)
		(pad "A6" thru_hole circle
			(at 9.99998 -0.100076)
			(size 0.9144 0.9144)
			(drill 0.508)
			(layers "*.Cu" "*.Mask")
			(remove_unused_layers no)
			(net "GND")
			(clearance 0.0508)
			(thermal_gap 0.0508)
		)
		(pad "B1" thru_hole circle
			(at 0 1.400048)
			(size 0.9144 0.9144)
			(drill 0.508)
			(layers "*.Cu" "*.Mask")
			(remove_unused_layers no)
			(net "ENET1G_3_MDI0N")
			(clearance 0.0508)
			(thermal_gap 0.0508)
		)
		(pad "B2" thru_hole circle
			(at 1.999996 1.299972)
			(size 0.9144 0.9144)
			(drill 0.508)
			(layers "*.Cu" "*.Mask")
			(remove_unused_layers no)
			(net "ENET1G_3_MDI2P")
			(clearance 0.0508)
			(thermal_gap 0.0508)
		)
		(pad "B3" thru_hole circle
			(at 3.999992 1.400048)
			(size 0.9144 0.9144)
			(drill 0.508)
			(layers "*.Cu" "*.Mask")
			(remove_unused_layers no)
			(net "ENET1G_3_MDI3N")
			(clearance 0.0508)
			(thermal_gap 0.0508)
		)
		(pad "B4" thru_hole circle
			(at 5.999988 1.299972)
			(size 0.9144 0.9144)
			(drill 0.508)
			(layers "*.Cu" "*.Mask")
			(remove_unused_layers no)
			(net "ENET1G_4_MDI0P")
			(clearance 0.0508)
			(thermal_gap 0.0508)
		)
		(pad "B5" thru_hole circle
			(at 7.999984 1.400048)
			(size 0.9144 0.9144)
			(drill 0.508)
			(layers "*.Cu" "*.Mask")
			(remove_unused_layers no)
			(net "ENET1G_4_MDI1N")
			(clearance 0.0508)
			(thermal_gap 0.0508)
		)
		(pad "B6" thru_hole circle
			(at 9.99998 1.299972)
			(size 0.9144 0.9144)
			(drill 0.508)
			(layers "*.Cu" "*.Mask")
			(remove_unused_layers no)
			(net "ENET1G_4_MDI3P")
			(clearance 0.0508)
			(thermal_gap 0.0508)
		)
		(pad "C1" thru_hole circle
			(at 0 2.800096)
			(size 0.9144 0.9144)
			(drill 0.508)
			(layers "*.Cu" "*.Mask")
			(remove_unused_layers no)
			(net "GND")
			(clearance 0.0508)
			(thermal_gap 0.0508)
		)
		(pad "C2" thru_hole circle
			(at 1.999996 2.70002)
			(size 0.9144 0.9144)
			(drill 0.508)
			(layers "*.Cu" "*.Mask")
			(remove_unused_layers no)
			(net "ENET1G_3_MDI2N")
			(clearance 0.0508)
			(thermal_gap 0.0508)
		)
		(pad "C3" thru_hole circle
			(at 3.999992 2.800096)
			(size 0.9144 0.9144)
			(drill 0.508)
			(layers "*.Cu" "*.Mask")
			(remove_unused_layers no)
			(net "GND")
			(clearance 0.0508)
			(thermal_gap 0.0508)
		)
		(pad "C4" thru_hole circle
			(at 5.999988 2.70002)
			(size 0.9144 0.9144)
			(drill 0.508)
			(layers "*.Cu" "*.Mask")
			(remove_unused_layers no)
			(net "ENET1G_4_MDI0N")
			(clearance 0.0508)
			(thermal_gap 0.0508)
		)
		(pad "C5" thru_hole circle
			(at 7.999984 2.800096)
			(size 0.9144 0.9144)
			(drill 0.508)
			(layers "*.Cu" "*.Mask")
			(remove_unused_layers no)
			(net "GND")
			(clearance 0.0508)
			(thermal_gap 0.0508)
		)
		(pad "C6" thru_hole circle
			(at 9.99998 2.70002)
			(size 0.9144 0.9144)
			(drill 0.508)
			(layers "*.Cu" "*.Mask")
			(remove_unused_layers no)
			(net "ENET1G_4_MDI3N")
			(clearance 0.0508)
			(thermal_gap 0.0508)
		)
		(pad "D1" thru_hole circle
			(at 0 4.19989)
			(size 0.9144 0.9144)
			(drill 0.508)
			(layers "*.Cu" "*.Mask")
			(remove_unused_layers no)
			(net "ENET10G_3_RDP")
			(clearance 0.0508)
			(thermal_gap 0.0508)
		)
		(pad "D2" thru_hole circle
			(at 1.999996 4.100068)
			(size 0.9144 0.9144)
			(drill 0.508)
			(layers "*.Cu" "*.Mask")
			(remove_unused_layers no)
			(net "GND")
			(clearance 0.0508)
			(thermal_gap 0.0508)
		)
		(pad "D3" thru_hole circle
			(at 3.999992 4.19989)
			(size 0.9144 0.9144)
			(drill 0.508)
			(layers "*.Cu" "*.Mask")
			(remove_unused_layers no)
			(net "ENET10G_3_SDA")
			(clearance 0.0508)
			(thermal_gap 0.0508)
		)
		(pad "D4" thru_hole circle
			(at 5.999988 4.100068)
			(size 0.9144 0.9144)
			(drill 0.508)
			(layers "*.Cu" "*.Mask")
			(remove_unused_layers no)
			(net "GND")
			(clearance 0.0508)
			(thermal_gap 0.0508)
		)
		(pad "D5" thru_hole circle
			(at 7.999984 4.19989)
			(size 0.9144 0.9144)
			(drill 0.508)
			(layers "*.Cu" "*.Mask")
			(remove_unused_layers no)
			(net "ENET1G_4_MDI2P")
			(clearance 0.0508)
			(thermal_gap 0.0508)
		)
		(pad "D6" thru_hole circle
			(at 9.99998 4.100068)
			(size 0.9144 0.9144)
			(drill 0.508)
			(layers "*.Cu" "*.Mask")
			(remove_unused_layers no)
			(net "GND")
			(clearance 0.0508)
			(thermal_gap 0.0508)
		)
		(pad "E1" thru_hole circle
			(at 0 5.599938)
			(size 0.9144 0.9144)
			(drill 0.508)
			(layers "*.Cu" "*.Mask")
			(remove_unused_layers no)
			(net "ENET10G_3_RDN")
			(clearance 0.0508)
			(thermal_gap 0.0508)
		)
		(pad "E2" thru_hole circle
			(at 1.999996 5.500116)
			(size 0.9144 0.9144)
			(drill 0.508)
			(layers "*.Cu" "*.Mask")
			(remove_unused_layers no)
			(net "ENET1G_3_MDI1P")
			(clearance 0.0508)
			(thermal_gap 0.0508)
		)
		(pad "E3" thru_hole circle
			(at 3.999992 5.599938)
			(size 0.9144 0.9144)
			(drill 0.508)
			(layers "*.Cu" "*.Mask")
			(remove_unused_layers no)
			(net "ENET10G_3_SCL")
			(clearance 0.0508)
			(thermal_gap 0.0508)
		)
		(pad "E4" thru_hole circle
			(at 5.999988 5.500116)
			(size 0.9144 0.9144)
			(drill 0.508)
			(layers "*.Cu" "*.Mask")
			(remove_unused_layers no)
			(net "ENET10G_4_SDA")
			(clearance 0.0508)
			(thermal_gap 0.0508)
		)
		(pad "E5" thru_hole circle
			(at 7.999984 5.599938)
			(size 0.9144 0.9144)
			(drill 0.508)
			(layers "*.Cu" "*.Mask")
			(remove_unused_layers no)
			(net "ENET1G_4_MDI2N")
			(clearance 0.0508)
			(thermal_gap 0.0508)
		)
		(pad "E6" thru_hole circle
			(at 9.99998 5.500116)
			(size 0.9144 0.9144)
			(drill 0.508)
			(layers "*.Cu" "*.Mask")
			(remove_unused_layers no)
			(net "ENET10G_4_RDP")
			(clearance 0.0508)
			(thermal_gap 0.0508)
		)
		(pad "F1" thru_hole circle
			(at 0 6.999986)
			(size 0.9144 0.9144)
			(drill 0.508)
			(layers "*.Cu" "*.Mask")
			(remove_unused_layers no)
			(net "GND")
			(clearance 0.0508)
			(thermal_gap 0.0508)
		)
		(pad "F2" thru_hole circle
			(at 1.999996 6.89991)
			(size 0.9144 0.9144)
			(drill 0.508)
			(layers "*.Cu" "*.Mask")
			(remove_unused_layers no)
			(net "ENET1G_3_MDI1N")
			(clearance 0.0508)
			(thermal_gap 0.0508)
		)
		(pad "F3" thru_hole circle
			(at 3.999992 6.999986)
			(size 0.9144 0.9144)
			(drill 0.508)
			(layers "*.Cu" "*.Mask")
			(remove_unused_layers no)
			(net "SKU_PIN_BLAD2_1")
			(clearance 0.0508)
			(thermal_gap 0.0508)
		)
		(pad "F4" thru_hole circle
			(at 5.999988 6.89991)
			(size 0.9144 0.9144)
			(drill 0.508)
			(layers "*.Cu" "*.Mask")
			(remove_unused_layers no)
			(net "ENET10G_4_SCL")
			(clearance 0.0508)
			(thermal_gap 0.0508)
		)
		(pad "F5" thru_hole circle
			(at 7.999984 6.999986)
			(size 0.9144 0.9144)
			(drill 0.508)
			(layers "*.Cu" "*.Mask")
			(remove_unused_layers no)
			(net "GND")
			(clearance 0.0508)
			(thermal_gap 0.0508)
		)
		(pad "F6" thru_hole circle
			(at 9.99998 6.89991)
			(size 0.9144 0.9144)
			(drill 0.508)
			(layers "*.Cu" "*.Mask")
			(remove_unused_layers no)
			(net "ENET10G_4_RDN")
			(clearance 0.0508)
			(thermal_gap 0.0508)
		)
		(pad "G1" thru_hole circle
			(at 0 8.400034)
			(size 0.9144 0.9144)
			(drill 0.508)
			(layers "*.Cu" "*.Mask")
			(remove_unused_layers no)
			(net "ENET10G_3_TDP")
			(clearance 0.0508)
			(thermal_gap 0.0508)
		)
		(pad "G2" thru_hole circle
			(at 1.999996 8.299958)
			(size 0.9144 0.9144)
			(drill 0.508)
			(layers "*.Cu" "*.Mask")
			(remove_unused_layers no)
			(net "GND")
			(clearance 0.0508)
			(thermal_gap 0.0508)
		)
		(pad "G3" thru_hole circle
			(at 3.999992 8.400034)
			(size 0.9144 0.9144)
			(drill 0.508)
			(layers "*.Cu" "*.Mask")
			(remove_unused_layers no)
			(net "NODE3_RXD")
			(clearance 0.0508)
			(thermal_gap 0.0508)
		)
		(pad "G4" thru_hole circle
			(at 5.999988 8.299958)
			(size 0.9144 0.9144)
			(drill 0.508)
			(layers "*.Cu" "*.Mask")
			(remove_unused_layers no)
			(net "NODE4_RXD")
			(clearance 0.0508)
			(thermal_gap 0.0508)
		)
		(pad "G5" thru_hole circle
			(at 7.999984 8.400034)
			(size 0.9144 0.9144)
			(drill 0.508)
			(layers "*.Cu" "*.Mask")
			(remove_unused_layers no)
			(net "NODE4_EN")
			(clearance 0.0508)
			(thermal_gap 0.0508)
		)
		(pad "G6" thru_hole circle
			(at 9.99998 8.299958)
			(size 0.9144 0.9144)
			(drill 0.508)
			(layers "*.Cu" "*.Mask")
			(remove_unused_layers no)
			(net "GND")
			(clearance 0.0508)
			(thermal_gap 0.0508)
		)
		(pad "H1" thru_hole circle
			(at 0 9.800082)
			(size 0.9144 0.9144)
			(drill 0.508)
			(layers "*.Cu" "*.Mask")
			(remove_unused_layers no)
			(net "ENET10G_3_TDN")
			(clearance 0.0508)
			(thermal_gap 0.0508)
		)
		(pad "H2" thru_hole circle
			(at 1.999996 9.700006)
			(size 0.9144 0.9144)
			(drill 0.508)
			(layers "*.Cu" "*.Mask")
			(remove_unused_layers no)
			(net "NODE3_EN")
			(clearance 0.0508)
			(thermal_gap 0.0508)
		)
		(pad "H3" thru_hole circle
			(at 3.999992 9.800082)
			(size 0.9144 0.9144)
			(drill 0.508)
			(layers "*.Cu" "*.Mask")
			(remove_unused_layers no)
			(net "NODE3_TXD")
			(clearance 0.0508)
			(thermal_gap 0.0508)
		)
		(pad "H4" thru_hole circle
			(at 5.999988 9.700006)
			(size 0.9144 0.9144)
			(drill 0.508)
			(layers "*.Cu" "*.Mask")
			(remove_unused_layers no)
			(net "NODE4_TXD")
			(clearance 0.0508)
			(thermal_gap 0.0508)
		)
		(pad "H5" thru_hole circle
			(at 7.999984 9.800082)
			(size 0.9144 0.9144)
			(drill 0.508)
			(layers "*.Cu" "*.Mask")
			(remove_unused_layers no)
			(net "SFP4_PRESENT_N")
			(clearance 0.0508)
			(thermal_gap 0.0508)
		)
		(pad "H6" thru_hole circle
			(at 9.99998 9.700006)
			(size 0.9144 0.9144)
			(drill 0.508)
			(layers "*.Cu" "*.Mask")
			(remove_unused_layers no)
			(net "ENET10G_4_TDP")
			(clearance 0.0508)
			(thermal_gap 0.0508)
		)
		(pad "I1" thru_hole circle
			(at 0 11.199876)
			(size 0.9144 0.9144)
			(drill 0.508)
			(layers "*.Cu" "*.Mask")
			(remove_unused_layers no)
			(net "GND")
			(clearance 0.0508)
			(thermal_gap 0.0508)
		)
		(pad "I2" thru_hole circle
			(at 1.999996 11.100054)
			(size 0.9144 0.9144)
			(drill 0.508)
			(layers "*.Cu" "*.Mask")
			(remove_unused_layers no)
			(net "SFP3_PRESENT_N")
			(clearance 0.0508)
			(thermal_gap 0.0508)
		)
		(pad "I3" thru_hole circle
			(at 3.999992 11.199876)
			(size 0.9144 0.9144)
			(drill 0.508)
			(layers "*.Cu" "*.Mask")
			(remove_unused_layers no)
			(net "P3V3_BLAD2")
			(clearance 0.0508)
			(thermal_gap 0.0508)
		)
		(pad "I4" thru_hole circle
			(at 5.999988 11.100054)
			(size 0.9144 0.9144)
			(drill 0.508)
			(layers "*.Cu" "*.Mask")
			(remove_unused_layers no)
			(net "SKU_PIN_BLAD2_2")
			(clearance 0.0508)
			(thermal_gap 0.0508)
		)
		(pad "I5" thru_hole circle
			(at 7.999984 11.199876)
			(size 0.9144 0.9144)
			(drill 0.508)
			(layers "*.Cu" "*.Mask")
			(remove_unused_layers no)
			(net "BLADE2_MATED_N")
			(clearance 0.0508)
			(thermal_gap 0.0508)
		)
		(pad "I6" thru_hole circle
			(at 9.99998 11.100054)
			(size 0.9144 0.9144)
			(drill 0.508)
			(layers "*.Cu" "*.Mask")
			(remove_unused_layers no)
			(net "ENET10G_4_TDN")
			(clearance 0.0508)
			(thermal_gap 0.0508)
		)
	)
)
